(kicad_pcb
	(version 20260206)
	(generator "pcbnew")
	(generator_version "10.0")
	(general
		(thickness 1.6)
		(legacy_teardrops no)
	)
	(paper "A4")
	(title_block
		(title "timecard-production-celestica-r4006 — R4006-B0001-02_R01.brd")
		(comment 1 "Time Appliance Project (Time Card) / footprints 116-120 of 1113")
	)
	(layers
		(0 "F.Cu" signal "TOP")
		(4 "In1.Cu" signal "L02_GND1")
		(6 "In2.Cu" signal "L03_SIG1")
		(8 "In3.Cu" signal "L04_GND2")
		(10 "In4.Cu" signal "L05_VCC1")
		(12 "In5.Cu" signal "L06_VCC2")
		(14 "In6.Cu" signal "L07_GND3")
		(16 "In7.Cu" signal "L08_SIG2")
		(18 "In8.Cu" signal "L09_GND4")
		(2 "B.Cu" signal "BOTTOM")
		(9 "F.Adhes" user "F.Adhesive")
		(11 "B.Adhes" user "B.Adhesive")
		(13 "F.Paste" user "Package Geometry/Pastemask Top")
		(15 "B.Paste" user "Package Geometry/Pastemask Bottom")
		(5 "F.SilkS" user "Ref Des/Silkscreen Top")
		(7 "B.SilkS" user "Ref Des/Silkscreen Bottom")
		(1 "F.Mask" user "Board Geometry/Soldermask Top")
		(3 "B.Mask" user "Board Geometry/Soldermask Bottom")
		(17 "Dwgs.User" user "User.Drawings")
		(19 "Cmts.User" user "User.Comments")
		(21 "Eco1.User" user "User.Eco1")
		(23 "Eco2.User" user "User.Eco2")
		(25 "Edge.Cuts" user "Board Geometry/Outline")
		(27 "Margin" user)
		(31 "F.CrtYd" user "Package Geometry/Place Bound Top")
		(29 "B.CrtYd" user "Package Geometry/Place Bound Bottom")
		(35 "F.Fab" user "Ref Des/Assembly Top")
		(33 "B.Fab" user "Ref Des/Assembly Bottom")
	)
	(footprint ""
		(layer "F.Cu")
		(at 1.500124 -24.5999 90)
		(property "Reference" "DS15"
			(at 2.66573 0.785876 0)
			(unlocked yes)
			(layer "F.SilkS")
			(effects
				(font
					(size 0.7874 0.5842)
					(thickness 0.1524)
				)
			)
		)
		(property "Value" ""
			(at 0 0 90)
			(layer "F.Fab")
			(effects
				(font
					(size 1.27 1.27)
				)
			)
		)
		(property "User Part Number" "PARTNUM*"
			(at 0.015494 4.486402 90)
			(unlocked yes)
			(layer "Cmts.User")
			(hide yes)
			(effects
				(font
					(size 0.7874 0.5842)
					(thickness 0.1524)
				)
			)
		)
		(property "Device Type" "LED_4P_V14-G170-10189-01"
			(at 0.015494 3.292602 90)
			(unlocked yes)
			(layer "F.Fab")
			(hide yes)
			(effects
				(font
					(size 0.7874 0.5842)
					(thickness 0.1524)
				)
			)
		)
		(duplicate_pad_numbers_are_jumpers no)
		(fp_line
			(start 1.378966 -0.829056)
			(end -1.378966 -0.829056)
			(stroke
				(width 0.1)
				(type default)
			)
			(layer "F.SilkS")
		)
		(fp_line
			(start -1.378966 -0.829056)
			(end -1.378966 -0.452628)
			(stroke
				(width 0.1)
				(type default)
			)
			(layer "F.SilkS")
		)
		(fp_line
			(start 1.998218 -0.452628)
			(end 1.378966 -0.452628)
			(stroke
				(width 0.1)
				(type default)
			)
			(layer "F.SilkS")
		)
		(fp_line
			(start 1.378966 -0.452628)
			(end 1.378966 -0.829056)
			(stroke
				(width 0.1)
				(type default)
			)
			(layer "F.SilkS")
		)
		(fp_line
			(start -1.378966 -0.452628)
			(end -1.998218 -0.452628)
			(stroke
				(width 0.1)
				(type default)
			)
			(layer "F.SilkS")
		)
		(fp_line
			(start -1.998218 -0.452628)
			(end -1.998218 1.103884)
			(stroke
				(width 0.1)
				(type default)
			)
			(layer "F.SilkS")
		)
		(fp_line
			(start 1.998218 1.103884)
			(end 1.998218 -0.452628)
			(stroke
				(width 0.1)
				(type default)
			)
			(layer "F.SilkS")
		)
		(fp_line
			(start -1.998218 1.103884)
			(end 1.998218 1.103884)
			(stroke
				(width 0.1)
				(type default)
			)
			(layer "F.SilkS")
		)
		(fp_poly
			(pts
				(xy 0.918464 -1.698498) (xy 1.223264 -1.46939) (xy 0.994664 -1.46939) (xy 0.994664 -1.24079) (xy 0.842264 -1.24079)
				(xy 0.842264 -1.46939) (xy 0.613664 -1.46939)
			)
			(stroke
				(width 0)
				(type default)
			)
			(fill yes)
			(layer "F.SilkS")
		)
		(fp_poly
			(pts
				(xy -0.73406 -1.677416) (xy -0.42926 -1.448308) (xy -0.65786 -1.448308) (xy -0.65786 -1.219708)
				(xy -0.81026 -1.219708) (xy -0.81026 -1.448308) (xy -1.03886 -1.448308)
			)
			(stroke
				(width 0)
				(type default)
			)
			(fill yes)
			(layer "F.SilkS")
		)
		(fp_poly
			(pts
				(xy -2.252218 1.357884) (xy -2.252218 -0.706628) (xy -1.632966 -0.706628) (xy -1.632966 -1.083056)
				(xy 1.632966 -1.083056) (xy 1.632966 -0.706628) (xy 2.252218 -0.706628) (xy 2.252218 1.357884)
			)
			(stroke
				(width 0)
				(type default)
			)
			(fill no)
			(layer "F.CrtYd")
		)
		(fp_line
			(start 1.124966 -0.575056)
			(end -1.124966 -0.575056)
			(stroke
				(width 0.1)
				(type default)
			)
			(layer "F.Fab")
		)
		(fp_line
			(start -1.124966 -0.575056)
			(end -1.124966 -0.075184)
			(stroke
				(width 0.1)
				(type default)
			)
			(layer "F.Fab")
		)
		(fp_line
			(start 1.325118 -0.075184)
			(end 1.124966 -0.075184)
			(stroke
				(width 0.1)
				(type default)
			)
			(layer "F.Fab")
		)
		(fp_line
			(start 1.124966 -0.075184)
			(end 1.124966 -0.575056)
			(stroke
				(width 0.1)
				(type default)
			)
			(layer "F.Fab")
		)
		(fp_line
			(start -1.124966 -0.075184)
			(end -1.325118 -0.075184)
			(stroke
				(width 0.1)
				(type default)
			)
			(layer "F.Fab")
		)
		(fp_line
			(start -1.325118 -0.075184)
			(end -1.325118 0.574802)
			(stroke
				(width 0.1)
				(type default)
			)
			(layer "F.Fab")
		)
		(fp_line
			(start 1.325118 0.574802)
			(end 1.325118 -0.075184)
			(stroke
				(width 0.1)
				(type default)
			)
			(layer "F.Fab")
		)
		(fp_line
			(start -1.325118 0.574802)
			(end 1.325118 0.574802)
			(stroke
				(width 0.1)
				(type default)
			)
			(layer "F.Fab")
		)
		(fp_poly
			(pts
				(xy 0.918464 -1.698498) (xy 1.223264 -1.46939) (xy 0.994664 -1.46939) (xy 0.994664 -1.24079) (xy 0.842264 -1.24079)
				(xy 0.842264 -1.46939) (xy 0.613664 -1.46939)
			)
			(stroke
				(width 0)
				(type default)
			)
			(fill yes)
			(layer "F.Fab")
		)
		(fp_poly
			(pts
				(xy -0.73406 -1.677416) (xy -0.42926 -1.448308) (xy -0.65786 -1.448308) (xy -0.65786 -1.219708)
				(xy -0.81026 -1.219708) (xy -0.81026 -1.448308) (xy -1.03886 -1.448308)
			)
			(stroke
				(width 0)
				(type default)
			)
			(fill yes)
			(layer "F.Fab")
		)
		(fp_text user "1"
			(at -2.2479 0.182626 90)
			(unlocked yes)
			(layer "F.SilkS")
			(effects
				(font
					(size 0.635 0.4064)
					(thickness 0.1524)
				)
			)
		)
		(fp_text user "3"
			(at 0.44196 1.833626 90)
			(unlocked yes)
			(layer "F.SilkS")
			(effects
				(font
					(size 0.635 0.4064)
					(thickness 0.1524)
				)
			)
		)
		(fp_text user "2"
			(at -0.8509 1.833626 90)
			(unlocked yes)
			(layer "F.SilkS")
			(effects
				(font
					(size 0.635 0.4064)
					(thickness 0.1524)
				)
			)
		)
		(fp_text user "4"
			(at 1.93929 1.420876 0)
			(unlocked yes)
			(layer "F.Fab")
			(effects
				(font
					(size 0.7874 0.5842)
					(thickness 0.1524)
				)
			)
		)
		(fp_text user "3"
			(at 0.79629 1.420876 0)
			(unlocked yes)
			(layer "F.Fab")
			(effects
				(font
					(size 0.7874 0.5842)
					(thickness 0.1524)
				)
			)
		)
		(fp_text user "2"
			(at -0.34671 1.420876 0)
			(unlocked yes)
			(layer "F.Fab")
			(effects
				(font
					(size 0.7874 0.5842)
					(thickness 0.1524)
				)
			)
		)
		(fp_text user "1"
			(at -1.39827 1.547876 0)
			(unlocked yes)
			(layer "F.Fab")
			(effects
				(font
					(size 0.7874 0.5842)
					(thickness 0.1524)
				)
			)
		)
		(pad "1" smd rect
			(at -1.325118 0.245872 90)
			(size 0.8382 0.889)
			(layers "F.Cu" "F.Mask" "F.Paste")
			(net "UNNAMED_14_LED4PV14_I266_1")
		)
		(pad "2" smd rect
			(at -0.424942 0.595884 90)
			(size 0.4572 0.508)
			(layers "F.Cu" "F.Mask" "F.Paste")
			(net "XP3R3V_FPGA")
		)
		(pad "3" smd rect
			(at 0.424942 0.595884 90)
			(size 0.4572 0.508)
			(layers "F.Cu" "F.Mask" "F.Paste")
			(net "UNNAMED_14_LED4PV14_I266_3")
		)
		(pad "4" smd rect
			(at 1.325118 0.245872 90)
			(size 0.8382 0.889)
			(layers "F.Cu" "F.Mask" "F.Paste")
			(net "UNNAMED_14_LED4PV14_I266_4")
		)
	)
	(footprint ""
		(layer "F.Cu")
		(at 60.325 -133.477)
		(property "Reference" "SP37"
			(at 0 0 0)
			(layer "F.SilkS")
			(hide yes)
			(effects
				(font
					(size 1.27 1.27)
				)
			)
		)
		(property "Value" ""
			(at 0 0 0)
			(layer "F.Fab")
			(effects
				(font
					(size 1.27 1.27)
				)
			)
		)
		(duplicate_pad_numbers_are_jumpers no)
	)
	(footprint ""
		(layer "F.Cu")
		(at 126.238 -39.116)
		(property "Reference" "TP62"
			(at -0.60325 0.5334 90)
			(unlocked yes)
			(layer "F.SilkS")
			(effects
				(font
					(size 0.635 0.4064)
					(thickness 0.1524)
				)
				(justify left)
			)
		)
		(property "Value" ""
			(at 0 0 0)
			(layer "F.Fab")
			(effects
				(font
					(size 1.27 1.27)
				)
			)
		)
		(property "Device Type" "TP_PIONT-TP010CT020B030_PTH-TPA"
			(at -1.341882 0.996696 0)
			(unlocked yes)
			(layer "F.Fab")
			(hide yes)
			(effects
				(font
					(size 0.7874 0.5842)
					(thickness 0.000001)
				)
				(justify left)
			)
		)
		(duplicate_pad_numbers_are_jumpers no)
		(fp_poly
			(pts
				(arc
					(start 0.889 0)
					(mid -0.889 0)
					(end 0.889 0)
				)
			)
			(stroke
				(width 0)
				(type default)
			)
			(fill no)
			(layer "B.CrtYd")
		)
		(fp_poly
			(pts
				(arc
					(start 0.889 0)
					(mid -0.889 0)
					(end 0.889 0)
				)
			)
			(stroke
				(width 0)
				(type default)
			)
			(fill no)
			(layer "F.CrtYd")
		)
		(pad "1" thru_hole circle
			(at 0 0)
			(size 0.508 0.508)
			(drill 0.254)
			(layers "*.Cu" "*.Mask")
			(remove_unused_layers no)
			(net "R_MAC_BITEOUT")
			(clearance 0.1016)
			(padstack
				(mode front_inner_back)
				(layer "Inner"
					(shape circle)
					(size 0.508 0.508)
					(clearance 0.1016)
				)
				(layer "B.Cu"
					(shape circle)
					(size 0.762 0.762)
					(clearance -0.0254)
				)
			)
		)
	)
	(footprint ""
		(layer "F.Cu")
		(at 19.685 -21.0312 -90)
		(property "Reference" "U19"
			(at -1.9558 -2.70637 90)
			(unlocked yes)
			(layer "F.SilkS")
			(effects
				(font
					(size 0.7874 0.5842)
					(thickness 0.1524)
				)
			)
		)
		(property "Value" ""
			(at 0 0 270)
			(layer "F.Fab")
			(effects
				(font
					(size 1.27 1.27)
				)
			)
		)
		(property "Device Type" "24LC16BT_I_ST_TSSOP8-G221-1017A"
			(at 0.0254 2.56667 270)
			(unlocked yes)
			(layer "F.Fab")
			(hide yes)
			(effects
				(font
					(size 0.7874 0.5842)
					(thickness 0.000001)
				)
			)
		)
		(property "User Part Number" "PARTNUM*"
			(at 0 3.45567 270)
			(unlocked yes)
			(layer "Cmts.User")
			(hide yes)
			(effects
				(font
					(size 0.7874 0.5842)
					(thickness 0.000001)
				)
			)
		)
		(duplicate_pad_numbers_are_jumpers no)
		(fp_line
			(start -4.0767 1.8034)
			(end -4.0767 -1.8034)
			(stroke
				(width 0.1)
				(type default)
			)
			(layer "F.SilkS")
		)
		(fp_line
			(start 4.0767 1.8034)
			(end -4.0767 1.8034)
			(stroke
				(width 0.1)
				(type default)
			)
			(layer "F.SilkS")
		)
		(fp_line
			(start -4.0767 -1.8034)
			(end 4.0767 -1.8034)
			(stroke
				(width 0.1)
				(type default)
			)
			(layer "F.SilkS")
		)
		(fp_line
			(start 4.0767 -1.8034)
			(end 4.0767 1.8034)
			(stroke
				(width 0.1)
				(type default)
			)
			(layer "F.SilkS")
		)
		(fp_poly
			(pts
				(arc
					(start -4.1148 -2.794)
					(mid -4.1148 -2.032)
					(end -4.1148 -2.794)
				)
			)
			(stroke
				(width 0)
				(type default)
			)
			(fill yes)
			(layer "F.SilkS")
		)
		(fp_poly
			(pts
				(xy -4.3307 2.0574) (xy 4.3307 2.0574) (xy 4.3307 -2.0574) (xy -4.3307 -2.0574)
			)
			(stroke
				(width 0)
				(type default)
			)
			(fill no)
			(layer "F.CrtYd")
		)
		(fp_line
			(start -2.2479 1.5494)
			(end -2.2479 -1.5494)
			(stroke
				(width 0.1)
				(type default)
			)
			(layer "F.Fab")
		)
		(fp_line
			(start 2.2479 1.5494)
			(end -2.2479 1.5494)
			(stroke
				(width 0.1)
				(type default)
			)
			(layer "F.Fab")
		)
		(fp_line
			(start -2.2479 -1.5494)
			(end 2.2479 -1.5494)
			(stroke
				(width 0.1)
				(type default)
			)
			(layer "F.Fab")
		)
		(fp_line
			(start 2.2479 -1.5494)
			(end 2.2479 1.5494)
			(stroke
				(width 0.1)
				(type default)
			)
			(layer "F.Fab")
		)
		(fp_poly
			(pts
				(arc
					(start -1.778 -1.397)
					(mid -1.778 -0.635)
					(end -1.778 -1.397)
				)
			)
			(stroke
				(width 0)
				(type default)
			)
			(fill yes)
			(layer "F.Fab")
		)
		(fp_text user "5"
			(at 5.01015 1.9431 0)
			(unlocked yes)
			(layer "F.SilkS")
			(effects
				(font
					(size 0.635 0.4064)
					(thickness 0.1524)
				)
				(justify left)
			)
		)
		(fp_text user "4"
			(at -4.76885 1.8161 0)
			(unlocked yes)
			(layer "F.SilkS")
			(effects
				(font
					(size 0.635 0.4064)
					(thickness 0.1524)
				)
				(justify left)
			)
		)
		(fp_text user "8"
			(at 3.61315 -2.1209 0)
			(unlocked yes)
			(layer "F.SilkS")
			(effects
				(font
					(size 0.635 0.4064)
					(thickness 0.1524)
				)
				(justify left)
			)
		)
		(fp_text user "5"
			(at 4.826 1.294384 90)
			(unlocked yes)
			(layer "F.Fab")
			(effects
				(font
					(size 0.7874 0.5842)
					(thickness 0.1524)
				)
				(justify left)
			)
		)
		(fp_text user "4"
			(at -4.6736 1.218184 90)
			(unlocked yes)
			(layer "F.Fab")
			(effects
				(font
					(size 0.7874 0.5842)
					(thickness 0.1524)
				)
				(justify left)
			)
		)
		(fp_text user "8"
			(at 4.826 -0.813816 90)
			(unlocked yes)
			(layer "F.Fab")
			(effects
				(font
					(size 0.7874 0.5842)
					(thickness 0.1524)
				)
				(justify left)
			)
		)
		(pad "1" smd rect
			(at -3.0353 -0.975106 270)
			(size 1.5748 0.3556)
			(layers "F.Cu" "F.Mask" "F.Paste")
			(net "UNNAMED_5_24LC16BTISTTSSOP8_I15")
		)
		(pad "2" smd rect
			(at -3.0353 -0.32512 270)
			(size 1.5748 0.3556)
			(layers "F.Cu" "F.Mask" "F.Paste")
			(net "UNNAMED_5_24LC16BTISTTSSOP8_I_1")
		)
		(pad "3" smd rect
			(at -3.0353 0.324866 270)
			(size 1.5748 0.3556)
			(layers "F.Cu" "F.Mask" "F.Paste")
			(net "UNNAMED_5_24LC16BTISTTSSOP8_I_2")
		)
		(pad "4" smd rect
			(at -3.0353 0.974852 270)
			(size 1.5748 0.3556)
			(layers "F.Cu" "F.Mask" "F.Paste")
			(net "SG")
		)
		(pad "5" smd rect
			(at 3.0353 0.974852 270)
			(size 1.5748 0.3556)
			(layers "F.Cu" "F.Mask" "F.Paste")
			(net "SEC_EEPROM_SDA")
		)
		(pad "6" smd rect
			(at 3.0353 0.324866 270)
			(size 1.5748 0.3556)
			(layers "F.Cu" "F.Mask" "F.Paste")
			(net "EEPROM_SCL")
		)
		(pad "7" smd rect
			(at 3.0353 -0.32512 270)
			(size 1.5748 0.3556)
			(layers "F.Cu" "F.Mask" "F.Paste")
			(net "SEC_EEPROM_WP")
		)
		(pad "8" smd rect
			(at 3.0353 -0.975106 270)
			(size 1.5748 0.3556)
			(layers "F.Cu" "F.Mask" "F.Paste")
			(net "XP3R3V_FPGA")
		)
	)
	(footprint ""
		(layer "F.Cu")
		(at 96.266 -24.638 180)
		(property "Reference" "C247"
			(at 12.065 -0.29337 0)
			(unlocked yes)
			(layer "F.SilkS")
			(effects
				(font
					(size 0.7874 0.5842)
					(thickness 0.1524)
				)
			)
		)
		(property "Value" "VAL*"
			(at 0.0762 2.067306 180)
			(unlocked yes)
			(layer "F.Fab")
			(hide yes)
			(effects
				(font
					(size 0.7874 0.5842)
					(thickness 0.1524)
				)
			)
		)
		(property "Tolerance" "TOL*"
			(at 0.0762 3.032506 180)
			(unlocked yes)
			(layer "Cmts.User")
			(hide yes)
			(effects
				(font
					(size 0.7874 0.5842)
					(thickness 0.1524)
				)
			)
		)
		(property "User Part Number" "PARTNUM*"
			(at 0.1016 4.023106 180)
			(unlocked yes)
			(layer "Cmts.User")
			(hide yes)
			(effects
				(font
					(size 0.7874 0.5842)
					(thickness 0.1524)
				)
			)
		)
		(property "Device Type" "CAPACITOR-G105-0C106-BM,10UF,2A"
			(at 0.0508 1.127506 180)
			(unlocked yes)
			(layer "F.Fab")
			(hide yes)
			(effects
				(font
					(size 0.7874 0.5842)
					(thickness 0.1524)
				)
			)
		)
		(duplicate_pad_numbers_are_jumpers no)
		(fp_line
			(start 1.143 0.5588)
			(end 1.143 -0.5588)
			(stroke
				(width 0.1)
				(type default)
			)
			(layer "F.SilkS")
		)
		(fp_line
			(start 1.143 -0.5588)
			(end -1.143 -0.5588)
			(stroke
				(width 0.1)
				(type default)
			)
			(layer "F.SilkS")
		)
		(fp_line
			(start -1.143 0.5588)
			(end 1.143 0.5588)
			(stroke
				(width 0.1)
				(type default)
			)
			(layer "F.SilkS")
		)
		(fp_line
			(start -1.143 -0.5588)
			(end -1.143 0.5588)
			(stroke
				(width 0.1)
				(type default)
			)
			(layer "F.SilkS")
		)
		(fp_rect
			(start 1.143 -0.5588)
			(end -1.143 0.5588)
			(stroke
				(width 0)
				(type default)
			)
			(fill no)
			(layer "F.CrtYd")
		)
		(fp_line
			(start 0.508 0.3048)
			(end 0.508 -0.3048)
			(stroke
				(width 0.1)
				(type default)
			)
			(layer "F.Fab")
		)
		(fp_line
			(start 0.508 -0.3048)
			(end -0.508 -0.3048)
			(stroke
				(width 0.1)
				(type default)
			)
			(layer "F.Fab")
		)
		(fp_line
			(start -0.508 0.3048)
			(end 0.508 0.3048)
			(stroke
				(width 0.1)
				(type default)
			)
			(layer "F.Fab")
		)
		(fp_line
			(start -0.508 -0.3048)
			(end -0.508 0.3048)
			(stroke
				(width 0.1)
				(type default)
			)
			(layer "F.Fab")
		)
		(pad "1" smd rect
			(at -0.5334 0 180)
			(size 0.7112 0.6096)
			(layers "F.Cu" "F.Mask" "F.Paste")
			(net "VDD3V3_OSC_125M")
		)
		(pad "2" smd rect
			(at 0.5334 0 180)
			(size 0.7112 0.6096)
			(layers "F.Cu" "F.Mask" "F.Paste")
			(net "SG")
		)
		(zone
			(layer "F.Cu")
			(hatch none 0.5)
			(connect_pads
				(clearance 0)
			)
			(min_thickness 0.25)
			(keepout
				(tracks allowed)
				(vias not_allowed)
				(pads allowed)
				(copperpour not_allowed)
				(footprints allowed)
			)
			(placement
				(enabled no)
				(sheetname "")
			)
			(fill
				(thermal_gap 0.5)
				(thermal_bridge_width 0.5)
				(island_removal_mode 0)
			)
			(polygon
				(pts
					(xy 96.1898 -24.3332) (xy 96.3422 -24.3332) (xy 96.3422 -24.9428) (xy 96.1898 -24.9428)
				)
			)
		)
	)
)
